# BASEBOARD_FAB2 (Tioga Pass) — schematic netlist excerpt (pin names and nets, part order shuffled) for the footprints in the layout excerpt that follows; sources: Cadence DE-HDL packaged netlist, KiCad conversion of Wiwynn_Tioga_Pass_MB.brd

C5G81  CAP_A  22.0UF 4V 20% X6S  pkg 0603V  page 243 : A = PVDDQ_GHJ ; B = GND
C2R11  SC4D7U16V3KX-GP  10%  pkg SMD-BCG5  page 240 : \1\ = P5V_STBY ; \2\ = AGND_P3V3_STBY
R6L13  RES  1.00K 1% CHIP  pkg 0402  page 98 : A = PVDDQ_DEF ; B = M_E_VREF

(kicad_pcb
	(version 20260206)
	(generator "pcbnew")
	(generator_version "10.0")
	(general
		(thickness 1.6)
		(legacy_teardrops no)
	)
	(paper "A4")
	(title_block
		(title "Wiwynn_Tioga_Pass_MB.brd")
		(comment 1 "Tioga Pass / footprints 4598-4600 of 4770")
	)
	(layers
		(0 "F.Cu" signal "TOP")
		(4 "In1.Cu" signal "L2GND")
		(6 "In2.Cu" signal "L3")
		(8 "In3.Cu" signal "L4GND")
		(10 "In4.Cu" signal "L5")
		(12 "In5.Cu" signal "L6GND")
		(14 "In6.Cu" signal "L7VCC")
		(16 "In7.Cu" signal "L8VCC")
		(18 "In8.Cu" signal "L9GND")
		(20 "In9.Cu" signal "L10")
		(22 "In10.Cu" signal "L11GND")
		(24 "In11.Cu" signal "L12")
		(26 "In12.Cu" signal "L13GND")
		(2 "B.Cu" signal "BOTTOM")
		(9 "F.Adhes" user "F.Adhesive")
		(11 "B.Adhes" user "B.Adhesive")
		(13 "F.Paste" user "Package Geometry/Pastemask Top")
		(15 "B.Paste" user "Package Geometry/Pastemask Bottom")
		(5 "F.SilkS" user "Ref Des/Silkscreen Top")
		(7 "B.SilkS" user "Ref Des/Silkscreen Bottom")
		(1 "F.Mask" user "Board Geometry/Soldermask Top")
		(3 "B.Mask" user "Board Geometry/Soldermask Bottom")
		(17 "Dwgs.User" user "User.Drawings")
		(19 "Cmts.User" user "User.Comments")
		(21 "Eco1.User" user "User.Eco1")
		(23 "Eco2.User" user "User.Eco2")
		(25 "Edge.Cuts" user "Board Geometry/Outline")
		(27 "Margin" user)
		(31 "F.CrtYd" user "Package Geometry/Place Bound Top")
		(29 "B.CrtYd" user "Package Geometry/Place Bound Bottom")
		(35 "F.Fab" user "Ref Des/Assembly Top")
		(33 "B.Fab" user "Ref Des/Assembly Bottom")
	)
	(footprint ""
		(layer "B.Cu")
		(at 87.158068 -12.954 -90)
		(property "Reference" "C5G81"
			(at -1.14681 0.76708 0)
			(unlocked yes)
			(layer "B.SilkS")
			(effects
				(font
					(size 0.7874 0.5842)
					(thickness 0.1524)
				)
				(justify mirror)
			)
		)
		(property "Value" ""
			(at 0 0 90)
			(layer "B.Fab")
			(effects
				(font
					(size 1.27 1.27)
				)
				(justify mirror)
			)
		)
		(duplicate_pad_numbers_are_jumpers no)
		(fp_rect
			(start 0.4953 1.6002)
			(end -0.4953 -0.2032)
			(stroke
				(width 0)
				(type default)
			)
			(fill no)
			(layer "B.CrtYd")
		)
		(fp_line
			(start -0.4953 1.6002)
			(end 0.4953 1.6002)
			(stroke
				(width 0.1)
				(type default)
			)
			(layer "B.Fab")
		)
		(fp_line
			(start 0.4953 1.6002)
			(end 0.4953 -0.2032)
			(stroke
				(width 0.1)
				(type default)
			)
			(layer "B.Fab")
		)
		(fp_line
			(start -0.4953 -0.2032)
			(end -0.4953 1.6002)
			(stroke
				(width 0.1)
				(type default)
			)
			(layer "B.Fab")
		)
		(fp_line
			(start 0.4953 -0.2032)
			(end -0.4953 -0.2032)
			(stroke
				(width 0.1)
				(type default)
			)
			(layer "B.Fab")
		)
		(pad "1" smd rect
			(at 0 0 90)
			(size 0.762 0.889)
			(layers "B.Cu" "B.Mask" "B.Paste")
			(net "PVDDQ_GHJ")
		)
		(pad "2" smd rect
			(at 0 1.397 90)
			(size 0.762 0.889)
			(layers "B.Cu" "B.Mask" "B.Paste")
			(net "GND")
		)
		(zone
			(layer "B.Cu")
			(hatch none 0.5)
			(connect_pads
				(clearance 0)
			)
			(min_thickness 0.25)
			(keepout
				(tracks not_allowed)
				(vias allowed)
				(pads allowed)
				(copperpour not_allowed)
				(footprints allowed)
			)
			(placement
				(enabled no)
				(sheetname "")
			)
			(fill
				(thermal_gap 0.5)
				(thermal_bridge_width 0.5)
				(island_removal_mode 0)
			)
			(polygon
				(pts
					(xy 86.205568 -12.573) (xy 86.713568 -12.573) (xy 86.713568 -13.335) (xy 86.205568 -13.335)
				)
			)
		)
	)
	(footprint ""
		(layer "B.Cu")
		(at 193.548 -144.4752 180)
		(property "Reference" "R6L13"
			(at 0 0 0)
			(layer "B.SilkS")
			(hide yes)
			(effects
				(font
					(size 1.27 1.27)
				)
				(justify mirror)
			)
		)
		(property "Value" ""
			(at 0 0 0)
			(layer "B.Fab")
			(effects
				(font
					(size 1.27 1.27)
				)
				(justify mirror)
			)
		)
		(duplicate_pad_numbers_are_jumpers no)
		(fp_poly
			(pts
				(xy 0.2794 -0.1016) (xy -0.2794 -0.1016) (xy -0.2794 0.9906) (xy 0.2794 0.9906)
			)
			(stroke
				(width 0)
				(type default)
			)
			(fill no)
			(layer "B.CrtYd")
		)
		(fp_line
			(start 0.2794 0.9906)
			(end -0.2794 0.9906)
			(stroke
				(width 0.1)
				(type default)
			)
			(layer "B.Fab")
		)
		(fp_line
			(start 0.2794 -0.1016)
			(end 0.2794 0.9906)
			(stroke
				(width 0.1)
				(type default)
			)
			(layer "B.Fab")
		)
		(fp_line
			(start -0.2794 0.9906)
			(end -0.2794 -0.1016)
			(stroke
				(width 0.1)
				(type default)
			)
			(layer "B.Fab")
		)
		(fp_line
			(start -0.2794 -0.1016)
			(end 0.2794 -0.1016)
			(stroke
				(width 0.1)
				(type default)
			)
			(layer "B.Fab")
		)
		(pad "1" smd rect
			(at 0 0)
			(size 0.508 0.508)
			(layers "B.Cu" "B.Mask" "B.Paste")
			(net "PVDDQ_DEF")
		)
		(pad "2" smd rect
			(at 0 0.889)
			(size 0.508 0.508)
			(layers "B.Cu" "B.Mask" "B.Paste")
			(net "M_E_VREF")
		)
		(zone
			(layer "B.Cu")
			(hatch none 0.5)
			(connect_pads
				(clearance 0)
			)
			(min_thickness 0.25)
			(keepout
				(tracks not_allowed)
				(vias allowed)
				(pads allowed)
				(copperpour not_allowed)
				(footprints allowed)
			)
			(placement
				(enabled no)
				(sheetname "")
			)
			(fill
				(thermal_gap 0.5)
				(thermal_bridge_width 0.5)
				(island_removal_mode 0)
			)
			(polygon
				(pts
					(xy 193.294 -145.1102) (xy 193.802 -145.1102) (xy 193.802 -144.7292) (xy 193.294 -144.7292)
				)
			)
		)
		(zone
			(layer "B.Cu")
			(hatch none 0.5)
			(connect_pads
				(clearance 0)
			)
			(min_thickness 0.25)
			(keepout
				(tracks allowed)
				(vias not_allowed)
				(pads allowed)
				(copperpour not_allowed)
				(footprints allowed)
			)
			(placement
				(enabled no)
				(sheetname "")
			)
			(fill
				(thermal_gap 0.5)
				(thermal_bridge_width 0.5)
				(island_removal_mode 0)
			)
			(polygon
				(pts
					(xy 193.294 -144.7292) (xy 193.802 -144.7292) (xy 193.802 -145.1102) (xy 193.294 -145.1102)
				)
			)
		)
	)
	(footprint ""
		(layer "B.Cu")
		(at 466.4583 -24.9555 -90)
		(property "Reference" "C2R11"
			(at 0 0 90)
			(layer "B.SilkS")
			(hide yes)
			(effects
				(font
					(size 1.27 1.27)
				)
				(justify mirror)
			)
		)
		(property "Value" "*"
			(at 0 -2.9337 270)
			(unlocked yes)
			(layer "B.Fab")
			(hide yes)
			(effects
				(font
					(size 1.27 1.016)
					(thickness 0.1524)
				)
				(justify mirror)
			)
		)
		(property "Device Type" "SC4D7U16V3KX-GP_SMD-BCG5-SC4D7A"
			(at 0 -4.4577 270)
			(unlocked yes)
			(layer "B.Fab")
			(hide yes)
			(effects
				(font
					(size 1.27 1.016)
					(thickness 0.1524)
				)
				(justify mirror)
			)
		)
		(duplicate_pad_numbers_are_jumpers no)
		(fp_line
			(start -0.508 0)
			(end 0.508 0)
			(stroke
				(width 0.2032)
				(type default)
			)
			(layer "B.SilkS")
		)
		(fp_rect
			(start 0.5842 1.3335)
			(end -0.5842 -1.3335)
			(stroke
				(width 0)
				(type default)
			)
			(fill no)
			(layer "B.CrtYd")
		)
		(fp_rect
			(start 0.5842 1.3335)
			(end -0.5842 -1.3335)
			(stroke
				(width 0)
				(type default)
			)
			(fill no)
			(layer "B.Fab")
		)
		(pad "1" smd custom
			(at 0 -0.762 90)
			(size 0.2159 0.2159)
			(layers "B.Cu" "B.Mask" "B.Paste")
			(net "P5V_STBY")
			(options
				(clearance outline)
				(anchor circle)
			)
			(primitives
				(gr_poly
					(pts
						(arc
							(start -0.3302 0.4318)
							(mid -0.402042 0.402042)
							(end -0.4318 0.3302)
						)
						(arc
							(start -0.4318 -0.3302)
							(mid -0.402042 -0.402042)
							(end -0.3302 -0.4318)
						)
						(arc
							(start 0.3302 -0.4318)
							(mid 0.402042 -0.402042)
							(end 0.4318 -0.3302)
						)
						(arc
							(start 0.4318 0.3302)
							(mid 0.402042 0.402042)
							(end 0.3302 0.4318)
						)
					)
					(width 0)
					(fill yes)
				)
			)
		)
		(pad "2" smd custom
			(at 0 0.762 90)
			(size 0.2159 0.2159)
			(layers "B.Cu" "B.Mask" "B.Paste")
			(net "AGND_P3V3_STBY")
			(options
				(clearance outline)
				(anchor circle)
			)
			(primitives
				(gr_poly
					(pts
						(arc
							(start -0.3302 0.4318)
							(mid -0.402042 0.402042)
							(end -0.4318 0.3302)
						)
						(arc
							(start -0.4318 -0.3302)
							(mid -0.402042 -0.402042)
							(end -0.3302 -0.4318)
						)
						(arc
							(start 0.3302 -0.4318)
							(mid 0.402042 -0.402042)
							(end 0.4318 -0.3302)
						)
						(arc
							(start 0.4318 0.3302)
							(mid 0.402042 0.402042)
							(end 0.3302 0.4318)
						)
					)
					(width 0)
					(fill yes)
				)
			)
		)
	)
)
